# T6G (Grand Teton) — schematic netlist excerpt (pin names and nets, part order shuffled) for the footprints in the layout excerpt that follows; sources: Cadence DE-HDL packaged netlist, KiCad conversion of 04192023_DAF0TMB3IC0_F0TG_MB_C_brd_V02_OCP.brd

PR6006  Q_RES  60.4K 1% CHIP  pkg 0402LF  page 269 : A = GND ; B = P1V8_AUX_MODE

Q4  MOSFET_DUAL_6P  2N7002KDW IC  pkg SOT363XD  page 155
  S1  = GND
  G1  = IRQ_LVC3_WAKE_N
  D2  = IRQ_WAKE_R_N
  S2  = GND
  G2  = IRQ_LVC3_WAKE
  D1  = IRQ_LVC3_WAKE

(kicad_pcb
	(version 20260206)
	(generator "pcbnew")
	(generator_version "10.0")
	(general
		(thickness 1.6)
		(legacy_teardrops no)
	)
	(paper "A4")
	(title_block
		(title "04192023_DAF0TMB3IC0_F0TG_MB_C_brd_V02_OCP.brd")
		(comment 1 "Grand Teton / footprints 2179-2180 of 8354")
	)
	(layers
		(0 "F.Cu" signal "TOP")
		(4 "In1.Cu" signal "GND")
		(6 "In2.Cu" signal "IN1")
		(8 "In3.Cu" signal "GND1")
		(10 "In4.Cu" signal "IN2")
		(12 "In5.Cu" signal "GND2")
		(14 "In6.Cu" signal "IN3")
		(16 "In7.Cu" signal "GND3")
		(18 "In8.Cu" signal "VCC")
		(20 "In9.Cu" signal "VCC1")
		(22 "In10.Cu" signal "GND4")
		(24 "In11.Cu" signal "IN4")
		(26 "In12.Cu" signal "GND5")
		(28 "In13.Cu" signal "IN5")
		(30 "In14.Cu" signal "GND6")
		(32 "In15.Cu" signal "IN6")
		(34 "In16.Cu" signal "GND7")
		(2 "B.Cu" signal "BOTTOM")
		(9 "F.Adhes" user "F.Adhesive")
		(11 "B.Adhes" user "B.Adhesive")
		(13 "F.Paste" user "Package Geometry/Pastemask Top")
		(15 "B.Paste" user "Package Geometry/Pastemask Bottom")
		(5 "F.SilkS" user "Ref Des/Silkscreen Top")
		(7 "B.SilkS" user "Ref Des/Silkscreen Bottom")
		(1 "F.Mask" user "Board Geometry/Soldermask Top")
		(3 "B.Mask" user "Board Geometry/Soldermask Bottom")
		(17 "Dwgs.User" user "User.Drawings")
		(19 "Cmts.User" user "User.Comments")
		(21 "Eco1.User" user "User.Eco1")
		(23 "Eco2.User" user "User.Eco2")
		(25 "Edge.Cuts" user "Board Geometry/Outline")
		(27 "Margin" user)
		(31 "F.CrtYd" user "Package Geometry/Place Bound Top")
		(29 "B.CrtYd" user "Package Geometry/Place Bound Bottom")
		(35 "F.Fab" user "Ref Des/Assembly Top")
		(33 "B.Fab" user "Ref Des/Assembly Bottom")
	)
	(footprint ""
		(layer "F.Cu")
		(at 145.050002 -81.018888 -90)
		(property "Reference" "PR6006"
			(at 0 0 270)
			(layer "F.SilkS")
			(hide yes)
			(effects
				(font
					(size 1.27 1.27)
				)
			)
		)
		(property "Value" ""
			(at 0 0 270)
			(layer "F.Fab")
			(effects
				(font
					(size 1.27 1.27)
				)
			)
		)
		(duplicate_pad_numbers_are_jumpers no)
		(fp_line
			(start -0.7874 0.4064)
			(end -0.7874 -0.4064)
			(stroke
				(width 0.1524)
				(type default)
			)
			(layer "F.SilkS")
		)
		(fp_line
			(start 0.7874 0.4064)
			(end -0.7874 0.4064)
			(stroke
				(width 0.1524)
				(type default)
			)
			(layer "F.SilkS")
		)
		(fp_line
			(start -0.7874 -0.4064)
			(end 0.7874 -0.4064)
			(stroke
				(width 0.1524)
				(type default)
			)
			(layer "F.SilkS")
		)
		(fp_line
			(start 0.7874 -0.4064)
			(end 0.7874 0.4064)
			(stroke
				(width 0.1524)
				(type default)
			)
			(layer "F.SilkS")
		)
		(fp_line
			(start -0.67945 0.3048)
			(end -0.67945 -0.305054)
			(stroke
				(width 0.1)
				(type default)
			)
			(layer "F.Fab")
		)
		(fp_line
			(start -0.12065 0.3048)
			(end -0.67945 0.3048)
			(stroke
				(width 0.1)
				(type default)
			)
			(layer "F.Fab")
		)
		(fp_line
			(start 0.120396 0.3048)
			(end 0.120396 0.2794)
			(stroke
				(width 0.1)
				(type default)
			)
			(layer "F.Fab")
		)
		(fp_line
			(start 0.67945 0.3048)
			(end 0.120396 0.3048)
			(stroke
				(width 0.1)
				(type default)
			)
			(layer "F.Fab")
		)
		(fp_line
			(start -0.12065 0.2794)
			(end -0.12065 0.3048)
			(stroke
				(width 0.1)
				(type default)
			)
			(layer "F.Fab")
		)
		(fp_line
			(start 0.120396 0.2794)
			(end -0.12065 0.2794)
			(stroke
				(width 0.1)
				(type default)
			)
			(layer "F.Fab")
		)
		(fp_line
			(start -0.12065 -0.2794)
			(end 0.12065 -0.2794)
			(stroke
				(width 0.1)
				(type default)
			)
			(layer "F.Fab")
		)
		(fp_line
			(start 0.12065 -0.2794)
			(end 0.12065 -0.3048)
			(stroke
				(width 0.1)
				(type default)
			)
			(layer "F.Fab")
		)
		(fp_line
			(start 0.12065 -0.3048)
			(end 0.67945 -0.3048)
			(stroke
				(width 0.1)
				(type default)
			)
			(layer "F.Fab")
		)
		(fp_line
			(start 0.67945 -0.3048)
			(end 0.67945 0.3048)
			(stroke
				(width 0.1)
				(type default)
			)
			(layer "F.Fab")
		)
		(fp_line
			(start -0.67945 -0.305054)
			(end -0.12065 -0.305054)
			(stroke
				(width 0.1)
				(type default)
			)
			(layer "F.Fab")
		)
		(fp_line
			(start -0.12065 -0.305054)
			(end -0.12065 -0.2794)
			(stroke
				(width 0.1)
				(type default)
			)
			(layer "F.Fab")
		)
		(pad "1" smd circle
			(at -0.40005 0 270)
			(size 0 0)
			(layers "F.Cu" "F.Mask" "F.Paste")
			(net "GND")
		)
		(pad "2" smd circle
			(at 0.40005 0 270)
			(size 0 0)
			(layers "F.Cu" "F.Mask" "F.Paste")
			(net "P1V8_AUX_MODE")
		)
	)
	(footprint ""
		(layer "F.Cu")
		(at 162.57143 -76.13142)
		(property "Reference" "Q4"
			(at -1.4224 -1.768348 0)
			(unlocked yes)
			(layer "F.SilkS")
			(effects
				(font
					(size 0.7874 0.5842)
					(thickness 0.1524)
				)
				(justify left)
			)
		)
		(property "Value" ""
			(at 0 0 0)
			(layer "F.Fab")
			(effects
				(font
					(size 1.27 1.27)
				)
			)
		)
		(duplicate_pad_numbers_are_jumpers no)
		(fp_line
			(start -1.332738 -1.100074)
			(end -0.4826 -1.100074)
			(stroke
				(width 0.1524)
				(type default)
			)
			(layer "F.SilkS")
		)
		(fp_line
			(start -1.332738 1.100074)
			(end -1.332738 -1.100074)
			(stroke
				(width 0.1524)
				(type default)
			)
			(layer "F.SilkS")
		)
		(fp_line
			(start -0.4826 -1.100074)
			(end 0 -0.541274)
			(stroke
				(width 0.1524)
				(type default)
			)
			(layer "F.SilkS")
		)
		(fp_line
			(start 0 -0.541274)
			(end 0.4826 -1.100074)
			(stroke
				(width 0.1524)
				(type default)
			)
			(layer "F.SilkS")
		)
		(fp_line
			(start 0.4826 -1.100074)
			(end 1.332738 -1.100074)
			(stroke
				(width 0.1524)
				(type default)
			)
			(layer "F.SilkS")
		)
		(fp_line
			(start 1.332738 -1.100074)
			(end 1.332738 1.100074)
			(stroke
				(width 0.1524)
				(type default)
			)
			(layer "F.SilkS")
		)
		(fp_line
			(start 1.332738 1.100074)
			(end -1.332738 1.100074)
			(stroke
				(width 0.1524)
				(type default)
			)
			(layer "F.SilkS")
		)
		(fp_poly
			(pts
				(xy -1.489456 -1.189482) (xy -2.23393 -1.43764) (xy -1.737614 -1.933956)
			)
			(stroke
				(width 0)
				(type default)
			)
			(fill yes)
			(layer "F.SilkS")
		)
		(fp_line
			(start -0.674878 -1.100074)
			(end 0.674878 -1.100074)
			(stroke
				(width 0.1)
				(type default)
			)
			(layer "F.Fab")
		)
		(fp_line
			(start -0.674878 1.100074)
			(end -0.674878 -1.100074)
			(stroke
				(width 0.1)
				(type default)
			)
			(layer "F.Fab")
		)
		(fp_line
			(start 0.674878 -1.100074)
			(end 0.674878 1.100074)
			(stroke
				(width 0.1)
				(type default)
			)
			(layer "F.Fab")
		)
		(fp_line
			(start 0.674878 1.100074)
			(end -0.674878 1.100074)
			(stroke
				(width 0.1)
				(type default)
			)
			(layer "F.Fab")
		)
		(fp_poly
			(pts
				(xy -2.2352 -0.298958) (xy -2.2352 -1.001014) (xy -1.533144 -0.649986)
			)
			(stroke
				(width 0)
				(type default)
			)
			(fill yes)
			(layer "F.Fab")
		)
		(pad "1" smd rect
			(at -0.94996 -0.649986 90)
			(size 0.4318 0.508)
			(layers "F.Cu" "F.Mask" "F.Paste")
			(net "GND")
		)
		(pad "2" smd rect
			(at -0.94996 0 90)
			(size 0.4318 0.508)
			(layers "F.Cu" "F.Mask" "F.Paste")
			(net "IRQ_LVC3_WAKE_N")
		)
		(pad "3" smd rect
			(at -0.94996 0.649986 90)
			(size 0.4318 0.508)
			(layers "F.Cu" "F.Mask" "F.Paste")
			(net "IRQ_WAKE_R_N")
		)
		(pad "4" smd rect
			(at 0.94996 0.649986 90)
			(size 0.4318 0.508)
			(layers "F.Cu" "F.Mask" "F.Paste")
			(net "GND")
		)
		(pad "5" smd rect
			(at 0.94996 0 90)
			(size 0.4318 0.508)
			(layers "F.Cu" "F.Mask" "F.Paste")
			(net "IRQ_LVC3_WAKE")
		)
		(pad "6" smd rect
			(at 0.94996 -0.649986 90)
			(size 0.4318 0.508)
			(layers "F.Cu" "F.Mask" "F.Paste")
			(net "IRQ_LVC3_WAKE")
		)
	)
)
